FILE_TYPE = CONNECTIVITY;
{Allegro Design Entry HDL 17.4-2019 S026 (4007227) 1/17/2022}
"PAGE_NUMBER" = 26;
0"NC";
1"P3E_CPU0_P4_RX_DP<3:0>";
2"P3E_CPU0_P4_RX_DN<3:0>";
3"P3E_CPU0_P4_TX_DN<3:0>";
4"P3E_CPU0_P4_TX_DP<3:0>";
5"P2E_CPU0_P5_TX_C_DN";
6"P2E_CPU0_P5_TX_C_DP";
7"P3E_CPU0_P4_TX_DN<3>";
8"WAFL_CPU0_TX0_CPU1_RX1_DP";
9"WAFL_CPU0_TX0_CPU1_RX1_DN"$PHYS_NET_NAME"P3E_M2_0_SATA_RX_DP";
10"P2E_CPU0_P5_TX_DN";
11"P2E_CPU0_P5_RX_DN";
12"P2E_CPU0_P5_RX_DP";
13"P2E_CPU0_P5_TX_DP";
14"P3E_CPU0_P4_RX_DN<0>";
15"P3E_CPU0_P4_TX_DP<2>";
16"P3E_CPU0_P4_TX_DN<2>";
17"P3E_CPU0_P4_TX_DP<3>";
18"WAFL_CPU1_TX1_CPU0_RX0_DN"$PHYS_NET_NAME"P3E_M2_0_SATA_RX_DP";
19"WAFL_CPU1_TX1_CPU0_RX0_DP";
20"P3E_CPU0_P4_RX_DN<2>";
21"P3E_CPU0_P4_RX_DN<3>";
22"P3E_CPU0_P4_RX_DP<3>";
23"P3E_CPU0_P4_TX_DP<0>";
24"P3E_CPU0_P4_TX_DP<1>";
25"P3E_CPU0_P4_TX_DN<0>";
26"P3E_CPU0_P4_RX_DP<0>";
27"P3E_CPU0_P4_TX_DN<1>";
28"P3E_CPU0_P4_RX_DP<1>";
29"P3E_CPU0_P4_RX_DN<1>";
30"P3E_CPU0_P4_RX_DP<2>";
%"TAP"
"6","(-6200,4850)","0","standard","I131";
;
CDS_LIB"standard"
BODY_TYPE"PLUMBING"
HDL_TAP"TRUE";
"B \NAC \NWC"2;
"S \NAC"
BN"3"21;
%"TAP"
"6","(-6200,4950)","0","standard","I132";
;
CDS_LIB"standard"
BODY_TYPE"PLUMBING"
HDL_TAP"TRUE";
"B \NAC \NWC"2;
"S \NAC"
BN"2"20;
%"TAP"
"6","(-6200,5050)","0","standard","I133";
;
CDS_LIB"standard"
BODY_TYPE"PLUMBING"
HDL_TAP"TRUE";
"B \NAC \NWC"2;
"S \NAC"
BN"1"29;
%"TAP"
"6","(-6200,5150)","0","standard","I134";
;
CDS_LIB"standard"
BODY_TYPE"PLUMBING"
HDL_TAP"TRUE";
"B \NAC \NWC"2;
"S \NAC"
BN"0"14;
%"TAP"
"6","(-6050,4900)","0","standard","I136";
;
CDS_LIB"standard"
BODY_TYPE"PLUMBING"
HDL_TAP"TRUE";
"B \NAC \NWC"1;
"S \NAC"
BN"3"22;
%"TAP"
"6","(-6050,5000)","0","standard","I137";
;
CDS_LIB"standard"
BODY_TYPE"PLUMBING"
HDL_TAP"TRUE";
"B \NAC \NWC"1;
"S \NAC"
BN"2"30;
%"TAP"
"6","(-6050,5200)","0","standard","I138";
;
CDS_LIB"standard"
BODY_TYPE"PLUMBING"
HDL_TAP"TRUE";
"B \NAC \NWC"1;
"S \NAC"
BN"0"26;
%"TAP"
"6","(-6050,5100)","0","standard","I139";
;
CDS_LIB"standard"
BODY_TYPE"PLUMBING"
HDL_TAP"TRUE";
"B \NAC \NWC"1;
"S \NAC"
BN"1"28;
%"TAP"
"6","(-3200,4900)","2","standard","I141";
;
CDS_LIB"standard"
BOM_COST"IO_SLOT"
ROOM"RISER1"
BODY_TYPE"PLUMBING"
HDL_TAP"TRUE";
"B \NAC \NWC"4;
"S \NAC"
BN"3"17;
%"TAP"
"6","(-3200,5000)","2","standard","I142";
;
CDS_LIB"standard"
BOM_COST"IO_SLOT"
ROOM"RISER1"
BODY_TYPE"PLUMBING"
HDL_TAP"TRUE";
"B \NAC \NWC"4;
"S \NAC"
BN"2"15;
%"TAP"
"6","(-3200,5100)","2","standard","I143";
;
CDS_LIB"standard"
BOM_COST"IO_SLOT"
ROOM"RISER1"
BODY_TYPE"PLUMBING"
HDL_TAP"TRUE";
"B \NAC \NWC"4;
"S \NAC"
BN"1"24;
%"TAP"
"6","(-3200,5200)","2","standard","I144";
;
CDS_LIB"standard"
BOM_COST"IO_SLOT"
ROOM"RISER1"
BODY_TYPE"PLUMBING"
HDL_TAP"TRUE";
"B \NAC \NWC"4;
"S \NAC"
BN"0"23;
%"TAP"
"6","(-3050,4850)","2","standard","I146";
;
CDS_LIB"standard"
BOM_COST"IO_SLOT"
ROOM"RISER1"
BODY_TYPE"PLUMBING"
HDL_TAP"TRUE";
"B \NAC \NWC"3;
"S \NAC"
BN"3"7;
%"TAP"
"6","(-3050,4950)","2","standard","I147";
;
CDS_LIB"standard"
BOM_COST"IO_SLOT"
ROOM"RISER1"
BODY_TYPE"PLUMBING"
HDL_TAP"TRUE";
"B \NAC \NWC"3;
"S \NAC"
BN"2"16;
%"TAP"
"6","(-3050,5150)","2","standard","I148";
;
CDS_LIB"standard"
BOM_COST"IO_SLOT"
ROOM"RISER1"
BODY_TYPE"PLUMBING"
HDL_TAP"TRUE";
"B \NAC \NWC"3;
"S \NAC"
BN"0"25;
%"TAP"
"6","(-3050,5050)","2","standard","I149";
;
CDS_LIB"standard"
BOM_COST"IO_SLOT"
ROOM"RISER1"
BODY_TYPE"PLUMBING"
HDL_TAP"TRUE";
"B \NAC \NWC"3;
"S \NAC"
BN"1"27;
%"Q_CAP_DIFFBUS"
"2","(-2700,4450)","0","pure_quanta","I156";
;
LOCATION"C2077"
$SEC"1"
CDS_SEC"1"
TOLERANCE"20%"
VALUE"DIFF BUS_0.22UF"
VOLTAGE"6.3V"
PACK_TYPE"C0201"
MATERIAL"X6S"
CDS_LIB"pure_quanta"
PIN_NAMES_ROTATE"True"
CDS_LMAN_SYM_OUTLINE"-25,50,25,-50"
PART_NUMBER"SP_CH4221MEE01";
"2"
$PN"2"6;
"1"
$PN"1"13;
%"Q_CAP_DIFFBUS"
"2","(-2700,4400)","0","pure_quanta","I157";
;
LOCATION"C2078"
$SEC"1"
CDS_SEC"1"
TOLERANCE"20%"
MATERIAL"X6S"
VOLTAGE"6.3V"
PACK_TYPE"C0201"
VALUE"DIFF BUS_0.22UF"
CDS_LIB"pure_quanta"
PIN_NAMES_ROTATE"True"
CDS_LMAN_SYM_OUTLINE"-25,50,25,-50"
PART_NUMBER"SP_CH4221MEE01";
"2"
$PN"2"5;
"1"
$PN"1"10;
%"GENOA_SP5"
"19","(-4575,4800)","0","pure_quanta","I59";
;
LOCATION"U25"
$SEC"19"
CDS_SEC"19"
MATERIAL"IO"
VALUE"SOCKET6096_13568-001"
PART_TYPE"SMLF"
CDS_LMAN_SYM_OUTLINE"-800,600,800,-600"
NEEDS_NO_SIZE"TRUE"
CDS_LIB"pure_quanta"
PART_NUMBER"DGA^6000030";
"WAFL_TXP1||P5_TXP1"
$PN"C47"0;
"WAFL_TXN1||P5_TXN1"
$PN"C48"0;
"WAFL_TXP0||P5_TXP0"
$PN"C50"8;
"WAFL_TXN0||P5_TXN0"
$PN"C51"9;
"WAFL_RXP1||P5_RXP1"
$PN"E46"0;
"WAFL_RXN1||P5_RXN1"
$PN"E47"0;
"WAFL_RXP0||P5_RXP0"
$PN"E49"19;
"WAFL_RXN0||P5_RXN0"
$PN"E50"18;
"P4_RXN1"
$PN"DG50"29;
"P4_RXN0"
$PN"DG53"14;
"P4_RXP1"
$PN"DG51"28;
"P4_TXN1"
$PN"DE49"27;
"P4_RXP0"
$PN"DG54"26;
"P4_TXN0"
$PN"DE52"25;
"P4_TXP1"
$PN"DE50"24;
"P4_TXP0"
$PN"DE53"23;
"P5_TXP3"
$PN"C41"0;
"P5_TXP2"
$PN"C44"13;
"P5_TXN3"
$PN"C42"0;
"P5_TXN2"
$PN"C45"10;
"P5_RXP3"
$PN"E40"0;
"P5_RXP2"
$PN"E43"12;
"P5_RXN3"
$PN"E41"0;
"P5_RXN2"
$PN"E44"11;
"P4_TXP3"
$PN"DE44"17;
"P4_TXP2"
$PN"DE47"15;
"P4_TXN3"
$PN"DE43"7;
"P4_TXN2"
$PN"DE46"16;
"P4_RXP3"
$PN"DG45"22;
"P4_RXP2"
$PN"DG48"30;
"P4_RXN3"
$PN"DG44"21;
"P4_RXN2"
$PN"DG47"20;
END.
